# SCM (Grand Teton) — schematic netlist excerpt (pin names and nets, part order shuffled) for the footprints in the layout excerpt that follows; sources: Cadence DE-HDL packaged netlist, KiCad conversion of 12092022_DA0F0TMDCD0_F0T_Management_Board_D_brd_V3_OCP.brd

J24  PICOPROBE_BXA  DELTA-L 4.0 EMPTY  pkg TRIANG_LAUNCH_3PXB  page 58
  \1_p\  = 85_10INCH_BOT_DP
  \2_n\  = 85_10INCH_BOT_DN
  \3_g\  = GND_P1

(kicad_pcb
	(version 20260206)
	(generator "pcbnew")
	(generator_version "10.0")
	(general
		(thickness 1.6)
		(legacy_teardrops no)
	)
	(paper "A4")
	(title_block
		(title "12092022_DA0F0TMDCD0_F0T_Management_Board_D_brd_V3_OCP.brd")
		(comment 1 "Grand Teton / footprints 1365-1365 of 1440")
	)
	(layers
		(0 "F.Cu" signal "TOP")
		(4 "In1.Cu" signal "GND")
		(6 "In2.Cu" signal "IN1")
		(8 "In3.Cu" signal "GND1")
		(10 "In4.Cu" signal "IN2")
		(12 "In5.Cu" signal "VCC")
		(14 "In6.Cu" signal "VCC1")
		(16 "In7.Cu" signal "IN3")
		(18 "In8.Cu" signal "GND2")
		(20 "In9.Cu" signal "IN4")
		(22 "In10.Cu" signal "GND3")
		(2 "B.Cu" signal "BOTTOM")
		(9 "F.Adhes" user "F.Adhesive")
		(11 "B.Adhes" user "B.Adhesive")
		(13 "F.Paste" user "Package Geometry/Pastemask Top")
		(15 "B.Paste" user "Package Geometry/Pastemask Bottom")
		(5 "F.SilkS" user "Ref Des/Silkscreen Top")
		(7 "B.SilkS" user "Ref Des/Silkscreen Bottom")
		(1 "F.Mask" user "Board Geometry/Soldermask Top")
		(3 "B.Mask" user "Board Geometry/Soldermask Bottom")
		(17 "Dwgs.User" user "User.Drawings")
		(19 "Cmts.User" user "User.Comments")
		(21 "Eco1.User" user "User.Eco1")
		(23 "Eco2.User" user "User.Eco2")
		(25 "Edge.Cuts" user "Board Geometry/Outline")
		(27 "Margin" user)
		(31 "F.CrtYd" user "Package Geometry/Place Bound Top")
		(29 "B.CrtYd" user "Package Geometry/Place Bound Bottom")
		(35 "F.Fab" user "Ref Des/Assembly Top")
		(33 "B.Fab" user "Ref Des/Assembly Bottom")
	)
	(footprint ""
		(layer "B.Cu")
		(at 101.2825 -54.403752 90)
		(property "Reference" "J24"
			(at -1.063752 -3.13817 270)
			(unlocked yes)
			(layer "B.SilkS")
			(effects
				(font
					(size 0.7874 0.5842)
					(thickness 0.1524)
				)
				(justify left mirror)
			)
		)
		(property "Value" ""
			(at 0 0 90)
			(layer "B.Fab")
			(effects
				(font
					(size 1.27 1.27)
				)
				(justify mirror)
			)
		)
		(duplicate_pad_numbers_are_jumpers no)
		(fp_line
			(start 1.2192 -2.1082)
			(end -1.2192 -2.1082)
			(stroke
				(width 0.1524)
				(type default)
			)
			(layer "B.SilkS")
		)
		(fp_line
			(start -1.2192 -2.1082)
			(end -1.2192 -0.466598)
			(stroke
				(width 0.1524)
				(type default)
			)
			(layer "B.SilkS")
		)
		(fp_line
			(start -1.2192 0.468122)
			(end -1.2192 2.1082)
			(stroke
				(width 0.1524)
				(type default)
			)
			(layer "B.SilkS")
		)
		(fp_line
			(start 1.2192 2.1082)
			(end 1.2192 -2.1082)
			(stroke
				(width 0.1524)
				(type default)
			)
			(layer "B.SilkS")
		)
		(fp_line
			(start -1.2192 2.1082)
			(end 1.2192 2.1082)
			(stroke
				(width 0.1524)
				(type default)
			)
			(layer "B.SilkS")
		)
		(pad "" np_thru_hole circle
			(at -3.4671 -1.27)
			(size 1.0414 1.0414)
			(drill 1.0414)
			(layers "*.Cu" "*.Mask")
			(clearance 0.381)
			(thermal_gap 0.381)
		)
		(pad "" np_thru_hole circle
			(at -3.4671 1.27)
			(size 1.0414 1.0414)
			(drill 1.0414)
			(layers "*.Cu" "*.Mask")
			(clearance 0.381)
			(thermal_gap 0.381)
		)
		(pad "" np_thru_hole circle
			(at 2.8829 -1.27)
			(size 1.0414 1.0414)
			(drill 1.0414)
			(layers "*.Cu" "*.Mask")
			(clearance 0.381)
			(thermal_gap 0.381)
		)
		(pad "" np_thru_hole circle
			(at 2.8829 1.27)
			(size 1.0414 1.0414)
			(drill 1.0414)
			(layers "*.Cu" "*.Mask")
			(clearance 0.381)
			(thermal_gap 0.381)
		)
		(pad "1" smd rect
			(at -0.8255 -0.249936)
			(size 0.3048 0.508)
			(layers "B.Cu" "B.Mask" "B.Paste")
			(net "85_10INCH_BOT_DP")
		)
		(pad "2" smd rect
			(at -0.8255 0.249936)
			(size 0.3048 0.508)
			(layers "B.Cu" "B.Mask" "B.Paste")
			(net "85_10INCH_BOT_DN")
		)
		(pad "3" smd circle
			(at 0 0 270)
			(size 0 0)
			(layers "B.Cu" "B.Mask" "B.Paste")
			(net "GND_P1")
		)
		(zone
			(layers "F.Cu" "B.Cu" "In1.Cu" "In2.Cu" "In3.Cu" "In4.Cu" "In5.Cu" "In6.Cu"
				"In7.Cu" "In8.Cu" "In9.Cu" "In10.Cu"
			)
			(hatch none 0.5)
			(connect_pads
				(clearance 0)
			)
			(min_thickness 0.25)
			(keepout
				(tracks not_allowed)
				(vias allowed)
				(pads allowed)
				(copperpour not_allowed)
				(footprints allowed)
			)
			(placement
				(enabled no)
				(sheetname "")
			)
			(fill
				(thermal_gap 0.5)
				(thermal_bridge_width 0.5)
				(island_removal_mode 0)
			)
			(polygon
				(pts
					(arc
						(start 100.9396 -57.286652)
						(mid 99.0854 -57.286652)
						(end 100.9396 -57.286652)
					)
				)
			)
		)
		(zone
			(layers "F.Cu" "B.Cu" "In1.Cu" "In2.Cu" "In3.Cu" "In4.Cu" "In5.Cu" "In6.Cu"
				"In7.Cu" "In8.Cu" "In9.Cu" "In10.Cu"
			)
			(hatch none 0.5)
			(connect_pads
				(clearance 0)
			)
			(min_thickness 0.25)
			(keepout
				(tracks not_allowed)
				(vias allowed)
				(pads allowed)
				(copperpour not_allowed)
				(footprints allowed)
			)
			(placement
				(enabled no)
				(sheetname "")
			)
			(fill
				(thermal_gap 0.5)
				(thermal_bridge_width 0.5)
				(island_removal_mode 0)
			)
			(polygon
				(pts
					(arc
						(start 100.9396 -50.936652)
						(mid 99.0854 -50.936652)
						(end 100.9396 -50.936652)
					)
				)
			)
		)
		(zone
			(layers "F.Cu" "B.Cu" "In1.Cu" "In2.Cu" "In3.Cu" "In4.Cu" "In5.Cu" "In6.Cu"
				"In7.Cu" "In8.Cu" "In9.Cu" "In10.Cu"
			)
			(hatch none 0.5)
			(connect_pads
				(clearance 0)
			)
			(min_thickness 0.25)
			(keepout
				(tracks not_allowed)
				(vias allowed)
				(pads allowed)
				(copperpour not_allowed)
				(footprints allowed)
			)
			(placement
				(enabled no)
				(sheetname "")
			)
			(fill
				(thermal_gap 0.5)
				(thermal_bridge_width 0.5)
				(island_removal_mode 0)
			)
			(polygon
				(pts
					(arc
						(start 103.4796 -57.286652)
						(mid 101.6254 -57.286652)
						(end 103.4796 -57.286652)
					)
				)
			)
		)
		(zone
			(layers "F.Cu" "B.Cu" "In1.Cu" "In2.Cu" "In3.Cu" "In4.Cu" "In5.Cu" "In6.Cu"
				"In7.Cu" "In8.Cu" "In9.Cu" "In10.Cu"
			)
			(hatch none 0.5)
			(connect_pads
				(clearance 0)
			)
			(min_thickness 0.25)
			(keepout
				(tracks not_allowed)
				(vias allowed)
				(pads allowed)
				(copperpour not_allowed)
				(footprints allowed)
			)
			(placement
				(enabled no)
				(sheetname "")
			)
			(fill
				(thermal_gap 0.5)
				(thermal_bridge_width 0.5)
				(island_removal_mode 0)
			)
			(polygon
				(pts
					(arc
						(start 103.4796 -50.936652)
						(mid 101.6254 -50.936652)
						(end 103.4796 -50.936652)
					)
				)
			)
		)
		(zone
			(layer "B.Cu")
			(hatch none 0.5)
			(connect_pads
				(clearance 0)
			)
			(min_thickness 0.25)
			(keepout
				(tracks not_allowed)
				(vias allowed)
				(pads allowed)
				(copperpour not_allowed)
				(footprints allowed)
			)
			(placement
				(enabled no)
				(sheetname "")
			)
			(fill
				(thermal_gap 0.5)
				(thermal_bridge_width 0.5)
				(island_removal_mode 0)
			)
			(polygon
				(pts
					(xy 100.73386 -53.286152) (xy 100.829364 -53.286152) (xy 100.829364 -53.883052) (xy 101.235764 -53.883052)
					(xy 101.235764 -53.286152) (xy 101.329236 -53.286152) (xy 101.329236 -53.883052) (xy 101.735636 -53.883052)
					(xy 101.735636 -53.286152) (xy 101.83114 -53.286152) (xy 101.83114 -53.984652) (xy 100.73386 -53.984652)
				)
			)
		)
	)
)
